(kicad_pcb
	(version 20260206)
	(generator "pcbnew")
	(generator_version "10.0")
	(general
		(thickness 1.6)
		(legacy_teardrops no)
	)
	(paper "A4")
	(title_block
		(title "03242023_DA0F0TMBIJ0_F0T_Motherboard_J_brd_V01_OCP.brd")
		(comment 1 "Grand Teton / footprints 3233-3238 of 6105")
	)
	(layers
		(0 "F.Cu" signal "TOP")
		(4 "In1.Cu" signal "GND")
		(6 "In2.Cu" signal "IN1")
		(8 "In3.Cu" signal "GND1")
		(10 "In4.Cu" signal "IN2")
		(12 "In5.Cu" signal "GND2")
		(14 "In6.Cu" signal "IN3")
		(16 "In7.Cu" signal "GND3")
		(18 "In8.Cu" signal "VCC")
		(20 "In9.Cu" signal "VCC1")
		(22 "In10.Cu" signal "GND4")
		(24 "In11.Cu" signal "IN4")
		(26 "In12.Cu" signal "GND5")
		(28 "In13.Cu" signal "IN5")
		(30 "In14.Cu" signal "GND6")
		(32 "In15.Cu" signal "IN6")
		(34 "In16.Cu" signal "GND7")
		(2 "B.Cu" signal "BOTTOM")
		(9 "F.Adhes" user "F.Adhesive")
		(11 "B.Adhes" user "B.Adhesive")
		(13 "F.Paste" user "Package Geometry/Pastemask Top")
		(15 "B.Paste" user "Package Geometry/Pastemask Bottom")
		(5 "F.SilkS" user "Ref Des/Silkscreen Top")
		(7 "B.SilkS" user "Ref Des/Silkscreen Bottom")
		(1 "F.Mask" user "Board Geometry/Soldermask Top")
		(3 "B.Mask" user "Board Geometry/Soldermask Bottom")
		(17 "Dwgs.User" user "User.Drawings")
		(19 "Cmts.User" user "User.Comments")
		(21 "Eco1.User" user "User.Eco1")
		(23 "Eco2.User" user "User.Eco2")
		(25 "Edge.Cuts" user "Board Geometry/Outline")
		(27 "Margin" user)
		(31 "F.CrtYd" user "Package Geometry/Place Bound Top")
		(29 "B.CrtYd" user "Package Geometry/Place Bound Bottom")
		(35 "F.Fab" user "Ref Des/Assembly Top")
		(33 "B.Fab" user "Ref Des/Assembly Bottom")
	)
	(footprint ""
		(layer "F.Cu")
		(at 209.74558 -131.846828 180)
		(property "Reference" "R1689"
			(at 0 0 180)
			(layer "F.SilkS")
			(hide yes)
			(effects
				(font
					(size 1.27 1.27)
				)
			)
		)
		(property "Value" ""
			(at 0 0 180)
			(layer "F.Fab")
			(effects
				(font
					(size 1.27 1.27)
				)
			)
		)
		(duplicate_pad_numbers_are_jumpers no)
		(fp_line
			(start 0.7874 0.4064)
			(end -0.7874 0.4064)
			(stroke
				(width 0.1524)
				(type default)
			)
			(layer "F.SilkS")
		)
		(fp_line
			(start 0.7874 -0.4064)
			(end 0.7874 0.4064)
			(stroke
				(width 0.1524)
				(type default)
			)
			(layer "F.SilkS")
		)
		(fp_line
			(start -0.7874 0.4064)
			(end -0.7874 -0.4064)
			(stroke
				(width 0.1524)
				(type default)
			)
			(layer "F.SilkS")
		)
		(fp_line
			(start -0.7874 -0.4064)
			(end 0.7874 -0.4064)
			(stroke
				(width 0.1524)
				(type default)
			)
			(layer "F.SilkS")
		)
		(fp_line
			(start 0.67945 0.3048)
			(end 0.120396 0.3048)
			(stroke
				(width 0.1)
				(type default)
			)
			(layer "F.Fab")
		)
		(fp_line
			(start 0.67945 -0.3048)
			(end 0.67945 0.3048)
			(stroke
				(width 0.1)
				(type default)
			)
			(layer "F.Fab")
		)
		(fp_line
			(start 0.12065 -0.2794)
			(end 0.12065 -0.3048)
			(stroke
				(width 0.1)
				(type default)
			)
			(layer "F.Fab")
		)
		(fp_line
			(start 0.12065 -0.3048)
			(end 0.67945 -0.3048)
			(stroke
				(width 0.1)
				(type default)
			)
			(layer "F.Fab")
		)
		(fp_line
			(start 0.120396 0.3048)
			(end 0.120396 0.2794)
			(stroke
				(width 0.1)
				(type default)
			)
			(layer "F.Fab")
		)
		(fp_line
			(start 0.120396 0.2794)
			(end -0.12065 0.2794)
			(stroke
				(width 0.1)
				(type default)
			)
			(layer "F.Fab")
		)
		(fp_line
			(start -0.12065 0.3048)
			(end -0.67945 0.3048)
			(stroke
				(width 0.1)
				(type default)
			)
			(layer "F.Fab")
		)
		(fp_line
			(start -0.12065 0.2794)
			(end -0.12065 0.3048)
			(stroke
				(width 0.1)
				(type default)
			)
			(layer "F.Fab")
		)
		(fp_line
			(start -0.12065 -0.2794)
			(end 0.12065 -0.2794)
			(stroke
				(width 0.1)
				(type default)
			)
			(layer "F.Fab")
		)
		(fp_line
			(start -0.12065 -0.305054)
			(end -0.12065 -0.2794)
			(stroke
				(width 0.1)
				(type default)
			)
			(layer "F.Fab")
		)
		(fp_line
			(start -0.67945 0.3048)
			(end -0.67945 -0.305054)
			(stroke
				(width 0.1)
				(type default)
			)
			(layer "F.Fab")
		)
		(fp_line
			(start -0.67945 -0.305054)
			(end -0.12065 -0.305054)
			(stroke
				(width 0.1)
				(type default)
			)
			(layer "F.Fab")
		)
		(pad "1" smd circle
			(at -0.40005 0 180)
			(size 0 0)
			(layers "F.Cu" "F.Mask" "F.Paste")
			(net "FM_COMP_P3V3_AUX_VIN")
		)
		(pad "2" smd circle
			(at 0.40005 0 180)
			(size 0 0)
			(layers "F.Cu" "F.Mask" "F.Paste")
			(net "GND")
		)
	)
	(footprint ""
		(layer "F.Cu")
		(at 327.770998 -190.74511 90)
		(property "Reference" "R4262"
			(at 0 0 90)
			(layer "F.SilkS")
			(hide yes)
			(effects
				(font
					(size 1.27 1.27)
				)
			)
		)
		(property "Value" ""
			(at 0 0 90)
			(layer "F.Fab")
			(effects
				(font
					(size 1.27 1.27)
				)
			)
		)
		(duplicate_pad_numbers_are_jumpers no)
		(fp_line
			(start 0.7874 -0.4064)
			(end 0.7874 0.4064)
			(stroke
				(width 0.1524)
				(type default)
			)
			(layer "F.SilkS")
		)
		(fp_line
			(start -0.7874 -0.4064)
			(end 0.7874 -0.4064)
			(stroke
				(width 0.1524)
				(type default)
			)
			(layer "F.SilkS")
		)
		(fp_line
			(start 0.7874 0.4064)
			(end -0.7874 0.4064)
			(stroke
				(width 0.1524)
				(type default)
			)
			(layer "F.SilkS")
		)
		(fp_line
			(start -0.7874 0.4064)
			(end -0.7874 -0.4064)
			(stroke
				(width 0.1524)
				(type default)
			)
			(layer "F.SilkS")
		)
		(fp_line
			(start -0.12065 -0.305054)
			(end -0.12065 -0.2794)
			(stroke
				(width 0.1)
				(type default)
			)
			(layer "F.Fab")
		)
		(fp_line
			(start -0.67945 -0.305054)
			(end -0.12065 -0.305054)
			(stroke
				(width 0.1)
				(type default)
			)
			(layer "F.Fab")
		)
		(fp_line
			(start 0.67945 -0.3048)
			(end 0.67945 0.3048)
			(stroke
				(width 0.1)
				(type default)
			)
			(layer "F.Fab")
		)
		(fp_line
			(start 0.12065 -0.3048)
			(end 0.67945 -0.3048)
			(stroke
				(width 0.1)
				(type default)
			)
			(layer "F.Fab")
		)
		(fp_line
			(start 0.12065 -0.2794)
			(end 0.12065 -0.3048)
			(stroke
				(width 0.1)
				(type default)
			)
			(layer "F.Fab")
		)
		(fp_line
			(start -0.12065 -0.2794)
			(end 0.12065 -0.2794)
			(stroke
				(width 0.1)
				(type default)
			)
			(layer "F.Fab")
		)
		(fp_line
			(start 0.120396 0.2794)
			(end -0.12065 0.2794)
			(stroke
				(width 0.1)
				(type default)
			)
			(layer "F.Fab")
		)
		(fp_line
			(start -0.12065 0.2794)
			(end -0.12065 0.3048)
			(stroke
				(width 0.1)
				(type default)
			)
			(layer "F.Fab")
		)
		(fp_line
			(start 0.67945 0.3048)
			(end 0.120396 0.3048)
			(stroke
				(width 0.1)
				(type default)
			)
			(layer "F.Fab")
		)
		(fp_line
			(start 0.120396 0.3048)
			(end 0.120396 0.2794)
			(stroke
				(width 0.1)
				(type default)
			)
			(layer "F.Fab")
		)
		(fp_line
			(start -0.12065 0.3048)
			(end -0.67945 0.3048)
			(stroke
				(width 0.1)
				(type default)
			)
			(layer "F.Fab")
		)
		(fp_line
			(start -0.67945 0.3048)
			(end -0.67945 -0.305054)
			(stroke
				(width 0.1)
				(type default)
			)
			(layer "F.Fab")
		)
		(pad "1" smd circle
			(at -0.40005 0 90)
			(size 0 0)
			(layers "F.Cu" "F.Mask" "F.Paste")
			(net "PVNN_TERM_CPU0")
		)
		(pad "2" smd circle
			(at 0.40005 0 90)
			(size 0 0)
			(layers "F.Cu" "F.Mask" "F.Paste")
			(net "PD_CPU0_BIST_ENABLE")
		)
	)
	(footprint ""
		(layer "F.Cu")
		(at 446.740026 -184.028842)
		(property "Reference" "PC1277"
			(at 0 0 0)
			(layer "F.SilkS")
			(hide yes)
			(effects
				(font
					(size 1.27 1.27)
				)
			)
		)
		(property "Value" ""
			(at 0 0 0)
			(layer "F.Fab")
			(effects
				(font
					(size 1.27 1.27)
				)
			)
		)
		(duplicate_pad_numbers_are_jumpers no)
		(fp_line
			(start -1.524 -0.762)
			(end 1.524 -0.762)
			(stroke
				(width 0.1524)
				(type default)
			)
			(layer "F.SilkS")
		)
		(fp_line
			(start -1.524 0.762)
			(end -1.524 -0.762)
			(stroke
				(width 0.1524)
				(type default)
			)
			(layer "F.SilkS")
		)
		(fp_line
			(start 1.524 -0.762)
			(end 1.524 0.762)
			(stroke
				(width 0.1524)
				(type default)
			)
			(layer "F.SilkS")
		)
		(fp_line
			(start 1.524 0.762)
			(end -1.524 0.762)
			(stroke
				(width 0.1524)
				(type default)
			)
			(layer "F.SilkS")
		)
		(fp_line
			(start -1.1049 -0.724916)
			(end -1.1049 0.724916)
			(stroke
				(width 0.1)
				(type default)
			)
			(layer "F.Fab")
		)
		(fp_line
			(start -1.1049 0.724916)
			(end 1.1049 0.724916)
			(stroke
				(width 0.1)
				(type default)
			)
			(layer "F.Fab")
		)
		(fp_line
			(start 1.1049 -0.724916)
			(end -1.1049 -0.724916)
			(stroke
				(width 0.1)
				(type default)
			)
			(layer "F.Fab")
		)
		(fp_line
			(start 1.1049 0.724916)
			(end 1.1049 -0.724916)
			(stroke
				(width 0.1)
				(type default)
			)
			(layer "F.Fab")
		)
		(pad "1" smd rect
			(at -0.889 0 180)
			(size 1.016 1.27)
			(layers "F.Cu" "F.Mask" "F.Paste")
			(net "PVNN_MAIN_CPU0")
		)
		(pad "2" smd rect
			(at 0.889 0 180)
			(size 1.016 1.27)
			(layers "F.Cu" "F.Mask" "F.Paste")
			(net "GND")
		)
	)
	(footprint ""
		(layer "F.Cu")
		(at 401.191984 -16.088614 90)
		(property "Reference" "C847"
			(at 0 0 90)
			(layer "F.SilkS")
			(hide yes)
			(effects
				(font
					(size 1.27 1.27)
				)
			)
		)
		(property "Value" ""
			(at 0 0 90)
			(layer "F.Fab")
			(effects
				(font
					(size 1.27 1.27)
				)
			)
		)
		(duplicate_pad_numbers_are_jumpers no)
		(fp_line
			(start 0.299974 -0.150114)
			(end 0.299974 0.150114)
			(stroke
				(width 0.1)
				(type default)
			)
			(layer "F.Fab")
		)
		(fp_line
			(start -0.299974 -0.150114)
			(end 0.299974 -0.150114)
			(stroke
				(width 0.1)
				(type default)
			)
			(layer "F.Fab")
		)
		(fp_line
			(start 0.299974 0.150114)
			(end -0.299974 0.150114)
			(stroke
				(width 0.1)
				(type default)
			)
			(layer "F.Fab")
		)
		(fp_line
			(start -0.299974 0.150114)
			(end -0.299974 -0.150114)
			(stroke
				(width 0.1)
				(type default)
			)
			(layer "F.Fab")
		)
		(pad "1" smd rect
			(at -0.2667 0 90)
			(size 0.3048 0.381)
			(layers "F.Cu" "F.Mask" "F.Paste")
			(net "P5E_CPU0_PE1_TX_C_DP<11>")
		)
		(pad "2" smd rect
			(at 0.2667 0 90)
			(size 0.3048 0.381)
			(layers "F.Cu" "F.Mask" "F.Paste")
			(net "P5E_CPU0_PE1_TX_DP<11>")
		)
	)
	(footprint ""
		(layer "F.Cu")
		(at 406.124664 -365.294926)
		(property "Reference" "R997"
			(at 0 0 0)
			(layer "F.SilkS")
			(hide yes)
			(effects
				(font
					(size 1.27 1.27)
				)
			)
		)
		(property "Value" ""
			(at 0 0 0)
			(layer "F.Fab")
			(effects
				(font
					(size 1.27 1.27)
				)
			)
		)
		(duplicate_pad_numbers_are_jumpers no)
		(fp_line
			(start -0.7874 -0.4064)
			(end 0.7874 -0.4064)
			(stroke
				(width 0.1524)
				(type default)
			)
			(layer "F.SilkS")
		)
		(fp_line
			(start -0.7874 0.4064)
			(end -0.7874 -0.4064)
			(stroke
				(width 0.1524)
				(type default)
			)
			(layer "F.SilkS")
		)
		(fp_line
			(start 0.7874 -0.4064)
			(end 0.7874 0.4064)
			(stroke
				(width 0.1524)
				(type default)
			)
			(layer "F.SilkS")
		)
		(fp_line
			(start 0.7874 0.4064)
			(end -0.7874 0.4064)
			(stroke
				(width 0.1524)
				(type default)
			)
			(layer "F.SilkS")
		)
		(fp_line
			(start -0.67945 -0.305054)
			(end -0.12065 -0.305054)
			(stroke
				(width 0.1)
				(type default)
			)
			(layer "F.Fab")
		)
		(fp_line
			(start -0.67945 0.3048)
			(end -0.67945 -0.305054)
			(stroke
				(width 0.1)
				(type default)
			)
			(layer "F.Fab")
		)
		(fp_line
			(start -0.12065 -0.305054)
			(end -0.12065 -0.2794)
			(stroke
				(width 0.1)
				(type default)
			)
			(layer "F.Fab")
		)
		(fp_line
			(start -0.12065 -0.2794)
			(end 0.12065 -0.2794)
			(stroke
				(width 0.1)
				(type default)
			)
			(layer "F.Fab")
		)
		(fp_line
			(start -0.12065 0.2794)
			(end -0.12065 0.3048)
			(stroke
				(width 0.1)
				(type default)
			)
			(layer "F.Fab")
		)
		(fp_line
			(start -0.12065 0.3048)
			(end -0.67945 0.3048)
			(stroke
				(width 0.1)
				(type default)
			)
			(layer "F.Fab")
		)
		(fp_line
			(start 0.120396 0.2794)
			(end -0.12065 0.2794)
			(stroke
				(width 0.1)
				(type default)
			)
			(layer "F.Fab")
		)
		(fp_line
			(start 0.120396 0.3048)
			(end 0.120396 0.2794)
			(stroke
				(width 0.1)
				(type default)
			)
			(layer "F.Fab")
		)
		(fp_line
			(start 0.12065 -0.3048)
			(end 0.67945 -0.3048)
			(stroke
				(width 0.1)
				(type default)
			)
			(layer "F.Fab")
		)
		(fp_line
			(start 0.12065 -0.2794)
			(end 0.12065 -0.3048)
			(stroke
				(width 0.1)
				(type default)
			)
			(layer "F.Fab")
		)
		(fp_line
			(start 0.67945 -0.3048)
			(end 0.67945 0.3048)
			(stroke
				(width 0.1)
				(type default)
			)
			(layer "F.Fab")
		)
		(fp_line
			(start 0.67945 0.3048)
			(end 0.120396 0.3048)
			(stroke
				(width 0.1)
				(type default)
			)
			(layer "F.Fab")
		)
		(pad "1" smd circle
			(at -0.40005 0)
			(size 0 0)
			(layers "F.Cu" "F.Mask" "F.Paste")
			(net "PU_PIROM_CPU0_SM_WP")
		)
		(pad "2" smd circle
			(at 0.40005 0)
			(size 0 0)
			(layers "F.Cu" "F.Mask" "F.Paste")
			(net "GND")
		)
	)
	(footprint ""
		(layer "F.Cu")
		(at 211.4296 -107.4166 -90)
		(property "Reference" "R4785"
			(at 0 0 270)
			(layer "F.SilkS")
			(hide yes)
			(effects
				(font
					(size 1.27 1.27)
				)
			)
		)
		(property "Value" ""
			(at 0 0 270)
			(layer "F.Fab")
			(effects
				(font
					(size 1.27 1.27)
				)
			)
		)
		(duplicate_pad_numbers_are_jumpers no)
		(fp_line
			(start -0.7874 0.4064)
			(end -0.7874 -0.4064)
			(stroke
				(width 0.1524)
				(type default)
			)
			(layer "F.SilkS")
		)
		(fp_line
			(start 0.7874 0.4064)
			(end -0.7874 0.4064)
			(stroke
				(width 0.1524)
				(type default)
			)
			(layer "F.SilkS")
		)
		(fp_line
			(start -0.7874 -0.4064)
			(end 0.7874 -0.4064)
			(stroke
				(width 0.1524)
				(type default)
			)
			(layer "F.SilkS")
		)
		(fp_line
			(start 0.7874 -0.4064)
			(end 0.7874 0.4064)
			(stroke
				(width 0.1524)
				(type default)
			)
			(layer "F.SilkS")
		)
		(fp_line
			(start -0.67945 0.3048)
			(end -0.67945 -0.305054)
			(stroke
				(width 0.1)
				(type default)
			)
			(layer "F.Fab")
		)
		(fp_line
			(start -0.12065 0.3048)
			(end -0.67945 0.3048)
			(stroke
				(width 0.1)
				(type default)
			)
			(layer "F.Fab")
		)
		(fp_line
			(start 0.120396 0.3048)
			(end 0.120396 0.2794)
			(stroke
				(width 0.1)
				(type default)
			)
			(layer "F.Fab")
		)
		(fp_line
			(start 0.67945 0.3048)
			(end 0.120396 0.3048)
			(stroke
				(width 0.1)
				(type default)
			)
			(layer "F.Fab")
		)
		(fp_line
			(start -0.12065 0.2794)
			(end -0.12065 0.3048)
			(stroke
				(width 0.1)
				(type default)
			)
			(layer "F.Fab")
		)
		(fp_line
			(start 0.120396 0.2794)
			(end -0.12065 0.2794)
			(stroke
				(width 0.1)
				(type default)
			)
			(layer "F.Fab")
		)
		(fp_line
			(start -0.12065 -0.2794)
			(end 0.12065 -0.2794)
			(stroke
				(width 0.1)
				(type default)
			)
			(layer "F.Fab")
		)
		(fp_line
			(start 0.12065 -0.2794)
			(end 0.12065 -0.3048)
			(stroke
				(width 0.1)
				(type default)
			)
			(layer "F.Fab")
		)
		(fp_line
			(start 0.12065 -0.3048)
			(end 0.67945 -0.3048)
			(stroke
				(width 0.1)
				(type default)
			)
			(layer "F.Fab")
		)
		(fp_line
			(start 0.67945 -0.3048)
			(end 0.67945 0.3048)
			(stroke
				(width 0.1)
				(type default)
			)
			(layer "F.Fab")
		)
		(fp_line
			(start -0.67945 -0.305054)
			(end -0.12065 -0.305054)
			(stroke
				(width 0.1)
				(type default)
			)
			(layer "F.Fab")
		)
		(fp_line
			(start -0.12065 -0.305054)
			(end -0.12065 -0.2794)
			(stroke
				(width 0.1)
				(type default)
			)
			(layer "F.Fab")
		)
		(pad "1" smd circle
			(at -0.40005 0 270)
			(size 0 0)
			(layers "F.Cu" "F.Mask" "F.Paste")
			(net "P3V3_AUX")
		)
		(pad "2" smd circle
			(at 0.40005 0 270)
			(size 0 0)
			(layers "F.Cu" "F.Mask" "F.Paste")
			(net "IRQ_UV_DETECT_N")
		)
	)
)
